FILE_TYPE = CONNECTIVITY;
{Allegro Design Entry HDL 17.2-2016 S081 (4005846) 1/11/2022}
"PAGE_NUMBER" = 208;
0"NC";
END.
